G04 ================== begin FILE IDENTIFICATION RECORD ==================*
G04 Layout Name:  17301-sa.brd*
G04 Film Name:    SE_REF_L1*
G04 File Format:  Gerber RS274X*
G04 File Origin:  Cadence Allegro 16.6-2015-S079*
G04 Origin Date:  Thu Jun 22 17:50:08 2017*
G04 *
G04 Layer:  BOARD GEOMETRY/PANEL_OUTLINE*
G04 Layer:  BOARD GEOMETRY/SE_REF_L1_TBL*
G04 Layer:  BOARD GEOMETRY/SE_REF_L1_TOP*
G04 *
G04 Offset:    (0.00 0.00)*
G04 Mirror:    No*
G04 Mode:      Positive*
G04 Rotation:  0*
G04 FullContactRelief:  No*
G04 UndefLineWidth:     6.00*
G04 ================== end FILE IDENTIFICATION RECORD ====================*
%FSLAX35Y35*MOIN*%
%IR0*IPPOS*OFA0.00000B0.00000*MIA0B0*SFA1.00000B1.00000*%
%ADD10C,.02*%
%ADD11C,.006*%
%ADD12C,.0072*%
G75*
%LPD*%
G75*
G54D10*
G01X615261Y627846D02*
X1332761D01*
G01X615261Y697146D02*
Y627846D01*
G01Y662496D02*
X1332761D01*
G01X615261Y697146D02*
X1332761D01*
G01X790261D02*
Y627846D01*
G01X1017761Y697146D02*
Y627846D01*
G01X1122761Y697146D02*
Y627846D01*
G01X1332761Y697146D02*
Y627846D01*
G54D11*
G01X-19340Y-32800D02*
Y-50300D01*
G01X-24362Y-32800D02*
X-14318D01*
G01X-5552Y-50300D02*
Y-32800D01*
G01Y-41258D02*
X-4460Y-39800D01*
X-3368Y-38925D01*
X-1622Y-38634D01*
X-312Y-38925D01*
X1217Y-40092D01*
X1872Y-41842D01*
Y-50300D01*
G01X15660Y-38634D02*
Y-50300D01*
G01Y-33967D02*
X15223Y-33675D01*
Y-33092D01*
X15660Y-32800D01*
X16097Y-33092D01*
Y-33675D01*
X15660Y-33967D01*
G01X29885Y-48259D02*
X30977Y-49425D01*
X32505Y-50300D01*
X33815D01*
X35125Y-49717D01*
X35998Y-48842D01*
X36435Y-47676D01*
X36217Y-45925D01*
X35343Y-45050D01*
X31413Y-43300D01*
X30540Y-41258D01*
X30977Y-39800D01*
X31850Y-38925D01*
X33160Y-38634D01*
X34470Y-38925D01*
X35780Y-39800D01*
G01X65103Y-54675D02*
X66632Y-55842D01*
X68378Y-56133D01*
X69906Y-55842D01*
X71217Y-54384D01*
X72090Y-52342D01*
Y-38634D01*
G01Y-40967D02*
X71217Y-39800D01*
X69906Y-38925D01*
X68378Y-38634D01*
X66632Y-39217D01*
X65540Y-40383D01*
X64666Y-42425D01*
X64230Y-44467D01*
X64448Y-46217D01*
X65322Y-48259D01*
X66632Y-49717D01*
X68378Y-50300D01*
X69688Y-50008D01*
X71217Y-48842D01*
X72090Y-47676D01*
G01X82385Y-42425D02*
X89372D01*
X88717Y-40383D01*
X87625Y-39217D01*
X86097Y-38634D01*
X84568Y-38925D01*
X83258Y-39800D01*
X82385Y-41842D01*
X81948Y-43592D01*
Y-45342D01*
X82385Y-47092D01*
X83477Y-48842D01*
X84787Y-50008D01*
X86315Y-50300D01*
X87843Y-49717D01*
X89372Y-47967D01*
G01X100103Y-50300D02*
Y-38634D01*
G01Y-40967D02*
X101195Y-39800D01*
X102287Y-38925D01*
X103815Y-38634D01*
X104906Y-38925D01*
X106217Y-39800D01*
G01X116730Y-50300D02*
Y-32800D01*
G01Y-41550D02*
X117822Y-39800D01*
X119132Y-38925D01*
X120442Y-38634D01*
X122406Y-39217D01*
X123717Y-40383D01*
X124590Y-42425D01*
Y-44758D01*
X124153Y-47092D01*
X123280Y-48842D01*
X121752Y-50008D01*
X120442Y-50300D01*
X119132Y-50008D01*
X117822Y-49134D01*
X116730Y-47676D01*
G01X134885Y-42425D02*
X141872D01*
X141217Y-40383D01*
X140125Y-39217D01*
X138597Y-38634D01*
X137068Y-38925D01*
X135758Y-39800D01*
X134885Y-41842D01*
X134448Y-43592D01*
Y-45342D01*
X134885Y-47092D01*
X135977Y-48842D01*
X137287Y-50008D01*
X138815Y-50300D01*
X140343Y-49717D01*
X141872Y-47967D01*
G01X152603Y-50300D02*
Y-38634D01*
G01Y-40967D02*
X153695Y-39800D01*
X154787Y-38925D01*
X156315Y-38634D01*
X157406Y-38925D01*
X158717Y-39800D01*
G01X190660Y-38634D02*
Y-50300D01*
G01Y-33967D02*
X190223Y-33675D01*
Y-33092D01*
X190660Y-32800D01*
X191097Y-33092D01*
Y-33675D01*
X190660Y-33967D01*
G01X204885Y-48259D02*
X205977Y-49425D01*
X207505Y-50300D01*
X208815D01*
X210125Y-49717D01*
X210998Y-48842D01*
X211435Y-47676D01*
X211217Y-45925D01*
X210343Y-45050D01*
X206413Y-43300D01*
X205540Y-41258D01*
X205977Y-39800D01*
X206850Y-38925D01*
X208160Y-38634D01*
X209470Y-38925D01*
X210780Y-39800D01*
G01X239666Y-54675D02*
X241195Y-55842D01*
X242505Y-56133D01*
X244252Y-55550D01*
X245562Y-54092D01*
X246217Y-51466D01*
Y-38634D01*
G01Y-33967D02*
X245780Y-33675D01*
Y-33092D01*
X246217Y-32800D01*
X246653Y-33092D01*
Y-33675D01*
X246217Y-33967D01*
G01X256948Y-38634D02*
Y-46800D01*
X257822Y-48842D01*
X259132Y-50008D01*
X260660Y-50300D01*
X262188Y-50008D01*
X263498Y-48842D01*
X264372Y-46800D01*
G01Y-50300D02*
Y-38634D01*
G01X274885Y-48259D02*
X275977Y-49425D01*
X277505Y-50300D01*
X278815D01*
X280125Y-49717D01*
X280998Y-48842D01*
X281435Y-47676D01*
X281217Y-45925D01*
X280343Y-45050D01*
X276413Y-43300D01*
X275540Y-41258D01*
X275977Y-39800D01*
X276850Y-38925D01*
X278160Y-38634D01*
X279470Y-38925D01*
X280780Y-39800D01*
G01X295660Y-32800D02*
Y-50300D01*
G01X292603Y-38634D02*
X298717D01*
G01X329350Y-50300D02*
Y-35425D01*
X329787Y-33967D01*
X330660Y-33092D01*
X331970Y-32800D01*
X333280Y-33383D01*
X333935Y-34842D01*
G01X331315Y-39800D02*
X326948D01*
G01X348160Y-50300D02*
X346850Y-50008D01*
X345540Y-48842D01*
X344666Y-46800D01*
X344230Y-44467D01*
X344666Y-42133D01*
X345540Y-40092D01*
X346850Y-38925D01*
X348160Y-38634D01*
X349470Y-38925D01*
X350780Y-40092D01*
X351653Y-42133D01*
X351872Y-44467D01*
X351653Y-46800D01*
X350780Y-48842D01*
X349470Y-50008D01*
X348160Y-50300D01*
G01X362603D02*
Y-38634D01*
G01Y-40967D02*
X363695Y-39800D01*
X364787Y-38925D01*
X366315Y-38634D01*
X367406Y-38925D01*
X368717Y-39800D01*
G01X396075Y-55550D02*
X397385Y-56133D01*
X399132Y-55550D01*
X400223Y-54384D01*
X401097Y-52925D01*
X402406Y-48259D01*
X405245Y-38634D01*
G01X398258D02*
X402406Y-48259D01*
G01X418160Y-50300D02*
X416850Y-50008D01*
X415540Y-48842D01*
X414666Y-46800D01*
X414230Y-44467D01*
X414666Y-42133D01*
X415540Y-40092D01*
X416850Y-38925D01*
X418160Y-38634D01*
X419470Y-38925D01*
X420780Y-40092D01*
X421653Y-42133D01*
X421872Y-44467D01*
X421653Y-46800D01*
X420780Y-48842D01*
X419470Y-50008D01*
X418160Y-50300D01*
G01X431948Y-38634D02*
Y-46800D01*
X432822Y-48842D01*
X434132Y-50008D01*
X435660Y-50300D01*
X437188Y-50008D01*
X438498Y-48842D01*
X439372Y-46800D01*
G01Y-50300D02*
Y-38634D01*
G01X450103Y-50300D02*
Y-38634D01*
G01Y-40967D02*
X451195Y-39800D01*
X452287Y-38925D01*
X453815Y-38634D01*
X454906Y-38925D01*
X456217Y-39800D01*
G01X485103Y-50300D02*
Y-38634D01*
G01Y-40967D02*
X486195Y-39800D01*
X487287Y-38925D01*
X488815Y-38634D01*
X489906Y-38925D01*
X491217Y-39800D01*
G01X502385Y-42425D02*
X509372D01*
X508717Y-40383D01*
X507625Y-39217D01*
X506097Y-38634D01*
X504568Y-38925D01*
X503258Y-39800D01*
X502385Y-41842D01*
X501948Y-43592D01*
Y-45342D01*
X502385Y-47092D01*
X503477Y-48842D01*
X504787Y-50008D01*
X506315Y-50300D01*
X507843Y-49717D01*
X509372Y-47967D01*
G01X521850Y-50300D02*
Y-35425D01*
X522287Y-33967D01*
X523160Y-33092D01*
X524470Y-32800D01*
X525780Y-33383D01*
X526435Y-34842D01*
G01X523815Y-39800D02*
X519448D01*
G01X537385Y-42425D02*
X544372D01*
X543717Y-40383D01*
X542625Y-39217D01*
X541097Y-38634D01*
X539568Y-38925D01*
X538258Y-39800D01*
X537385Y-41842D01*
X536948Y-43592D01*
Y-45342D01*
X537385Y-47092D01*
X538477Y-48842D01*
X539787Y-50008D01*
X541315Y-50300D01*
X542843Y-49717D01*
X544372Y-47967D01*
G01X555103Y-50300D02*
Y-38634D01*
G01Y-40967D02*
X556195Y-39800D01*
X557287Y-38925D01*
X558815Y-38634D01*
X559906Y-38925D01*
X561217Y-39800D01*
G01X572385Y-42425D02*
X579372D01*
X578717Y-40383D01*
X577625Y-39217D01*
X576097Y-38634D01*
X574568Y-38925D01*
X573258Y-39800D01*
X572385Y-41842D01*
X571948Y-43592D01*
Y-45342D01*
X572385Y-47092D01*
X573477Y-48842D01*
X574787Y-50008D01*
X576315Y-50300D01*
X577843Y-49717D01*
X579372Y-47967D01*
G01X589448Y-50300D02*
Y-38634D01*
G01Y-41550D02*
X590322Y-40092D01*
X591632Y-38925D01*
X593378Y-38634D01*
X594906Y-38925D01*
X596217Y-40092D01*
X596872Y-42133D01*
Y-50300D01*
G01X614153Y-40092D02*
X612625Y-38925D01*
X611315Y-38634D01*
X609568Y-39217D01*
X608258Y-40383D01*
X607385Y-42425D01*
X607166Y-44467D01*
X607385Y-46509D01*
X608258Y-48259D01*
X609568Y-49717D01*
X611315Y-50300D01*
X612843Y-49717D01*
X614153Y-48550D01*
G01X624885Y-42425D02*
X631872D01*
X631217Y-40383D01*
X630125Y-39217D01*
X628597Y-38634D01*
X627068Y-38925D01*
X625758Y-39800D01*
X624885Y-41842D01*
X624448Y-43592D01*
Y-45342D01*
X624885Y-47092D01*
X625977Y-48842D01*
X627287Y-50008D01*
X628815Y-50300D01*
X630343Y-49717D01*
X631872Y-47967D01*
G01X663160Y-32800D02*
Y-50300D01*
G01X660103Y-38634D02*
X666217D01*
G01X680660Y-50300D02*
X679350Y-50008D01*
X678040Y-48842D01*
X677166Y-46800D01*
X676730Y-44467D01*
X677166Y-42133D01*
X678040Y-40092D01*
X679350Y-38925D01*
X680660Y-38634D01*
X681970Y-38925D01*
X683280Y-40092D01*
X684153Y-42133D01*
X684372Y-44467D01*
X684153Y-46800D01*
X683280Y-48842D01*
X681970Y-50008D01*
X680660Y-50300D01*
G01X714350D02*
Y-35425D01*
X714787Y-33967D01*
X715660Y-33092D01*
X716970Y-32800D01*
X718280Y-33383D01*
X718935Y-34842D01*
G01X716315Y-39800D02*
X711948D01*
G01X733160Y-38634D02*
Y-50300D01*
G01Y-33967D02*
X732723Y-33675D01*
Y-33092D01*
X733160Y-32800D01*
X733597Y-33092D01*
Y-33675D01*
X733160Y-33967D01*
G01X746948Y-50300D02*
Y-38634D01*
G01Y-41550D02*
X747822Y-40092D01*
X749132Y-38925D01*
X750878Y-38634D01*
X752406Y-38925D01*
X753717Y-40092D01*
X754372Y-42133D01*
Y-50300D01*
G01X772090Y-32800D02*
Y-50300D01*
G01Y-47676D02*
X771217Y-49134D01*
X769906Y-50008D01*
X768378Y-50300D01*
X766632Y-49717D01*
X765322Y-48259D01*
X764448Y-46509D01*
X764230Y-44467D01*
X764448Y-42425D01*
X765322Y-40675D01*
X766632Y-39217D01*
X768378Y-38634D01*
X769906Y-38925D01*
X770998Y-39509D01*
X772090Y-40675D01*
G01X803160Y-32800D02*
Y-50300D01*
G01X800103Y-38634D02*
X806217D01*
G01X816948Y-50300D02*
Y-32800D01*
G01Y-41258D02*
X818040Y-39800D01*
X819132Y-38925D01*
X820878Y-38634D01*
X822188Y-38925D01*
X823717Y-40092D01*
X824372Y-41842D01*
Y-50300D01*
G01X834885Y-42425D02*
X841872D01*
X841217Y-40383D01*
X840125Y-39217D01*
X838597Y-38634D01*
X837068Y-38925D01*
X835758Y-39800D01*
X834885Y-41842D01*
X834448Y-43592D01*
Y-45342D01*
X834885Y-47092D01*
X835977Y-48842D01*
X837287Y-50008D01*
X838815Y-50300D01*
X840343Y-49717D01*
X841872Y-47967D01*
G01X868575D02*
X870322Y-49425D01*
X872287Y-50300D01*
X874033D01*
X875780Y-49425D01*
X877090Y-47967D01*
X877745Y-45925D01*
X877308Y-43884D01*
X876217Y-42133D01*
X874252Y-40967D01*
X871632Y-40383D01*
X870103Y-39217D01*
X869448Y-37175D01*
X869885Y-35133D01*
X870977Y-33675D01*
X872505Y-32800D01*
X874033D01*
X875562Y-33383D01*
X876872Y-34842D01*
G01X895027Y-50300D02*
X886293D01*
Y-32800D01*
X895027D01*
G01X891533Y-41258D02*
X886293D01*
G01X925660Y-38634D02*
Y-50300D01*
G01Y-33967D02*
X925223Y-33675D01*
Y-33092D01*
X925660Y-32800D01*
X926097Y-33092D01*
Y-33675D01*
X925660Y-33967D01*
G01X936610Y-50300D02*
Y-38634D01*
G01Y-41842D02*
X937265Y-40383D01*
X938357Y-39217D01*
X939885Y-38634D01*
X941413Y-39217D01*
X942505Y-40383D01*
X943160Y-41842D01*
Y-50300D01*
G01Y-41842D02*
X943815Y-40383D01*
X944906Y-39217D01*
X946435Y-38634D01*
X947963Y-39217D01*
X949055Y-40383D01*
X949710Y-42133D01*
Y-50300D01*
G01X956730Y-56133D02*
Y-38634D01*
G01Y-41258D02*
X957822Y-39800D01*
X958913Y-38925D01*
X960660Y-38634D01*
X962188Y-38925D01*
X963717Y-40383D01*
X964372Y-42425D01*
X964590Y-44467D01*
X964372Y-46509D01*
X963717Y-48550D01*
X962406Y-49717D01*
X960660Y-50300D01*
X959132Y-50008D01*
X957603Y-49134D01*
X956730Y-47967D01*
G01X974885Y-42425D02*
X981872D01*
X981217Y-40383D01*
X980125Y-39217D01*
X978597Y-38634D01*
X977068Y-38925D01*
X975758Y-39800D01*
X974885Y-41842D01*
X974448Y-43592D01*
Y-45342D01*
X974885Y-47092D01*
X975977Y-48842D01*
X977287Y-50008D01*
X978815Y-50300D01*
X980343Y-49717D01*
X981872Y-47967D01*
G01X999590Y-32800D02*
Y-50300D01*
G01Y-47676D02*
X998717Y-49134D01*
X997406Y-50008D01*
X995878Y-50300D01*
X994132Y-49717D01*
X992822Y-48259D01*
X991948Y-46509D01*
X991730Y-44467D01*
X991948Y-42425D01*
X992822Y-40675D01*
X994132Y-39217D01*
X995878Y-38634D01*
X997406Y-38925D01*
X998498Y-39509D01*
X999590Y-40675D01*
G01X1017090Y-50300D02*
Y-38634D01*
G01Y-40675D02*
X1016217Y-39509D01*
X1014906Y-38925D01*
X1013378Y-38634D01*
X1011850Y-39217D01*
X1010540Y-40383D01*
X1009666Y-42133D01*
X1009230Y-44467D01*
X1009666Y-46800D01*
X1010540Y-48550D01*
X1011850Y-49717D01*
X1013378Y-50300D01*
X1014906Y-50008D01*
X1016217Y-49134D01*
X1017090Y-47967D01*
G01X1026948Y-50300D02*
Y-38634D01*
G01Y-41550D02*
X1027822Y-40092D01*
X1029132Y-38925D01*
X1030878Y-38634D01*
X1032406Y-38925D01*
X1033717Y-40092D01*
X1034372Y-42133D01*
Y-50300D01*
G01X1051653Y-40092D02*
X1050125Y-38925D01*
X1048815Y-38634D01*
X1047068Y-39217D01*
X1045758Y-40383D01*
X1044885Y-42425D01*
X1044666Y-44467D01*
X1044885Y-46509D01*
X1045758Y-48259D01*
X1047068Y-49717D01*
X1048815Y-50300D01*
X1050343Y-49717D01*
X1051653Y-48550D01*
G01X1062385Y-42425D02*
X1069372D01*
X1068717Y-40383D01*
X1067625Y-39217D01*
X1066097Y-38634D01*
X1064568Y-38925D01*
X1063258Y-39800D01*
X1062385Y-41842D01*
X1061948Y-43592D01*
Y-45342D01*
X1062385Y-47092D01*
X1063477Y-48842D01*
X1064787Y-50008D01*
X1066315Y-50300D01*
X1067843Y-49717D01*
X1069372Y-47967D01*
G01X1100660Y-32800D02*
Y-50300D01*
G01X1097603Y-38634D02*
X1103717D01*
G01X1115103Y-50300D02*
Y-38634D01*
G01Y-40967D02*
X1116195Y-39800D01*
X1117287Y-38925D01*
X1118815Y-38634D01*
X1119906Y-38925D01*
X1121217Y-39800D01*
G01X1139590Y-50300D02*
Y-38634D01*
G01Y-40675D02*
X1138717Y-39509D01*
X1137406Y-38925D01*
X1135878Y-38634D01*
X1134350Y-39217D01*
X1133040Y-40383D01*
X1132166Y-42133D01*
X1131730Y-44467D01*
X1132166Y-46800D01*
X1133040Y-48550D01*
X1134350Y-49717D01*
X1135878Y-50300D01*
X1137406Y-50008D01*
X1138717Y-49134D01*
X1139590Y-47967D01*
G01X1156653Y-40092D02*
X1155125Y-38925D01*
X1153815Y-38634D01*
X1152068Y-39217D01*
X1150758Y-40383D01*
X1149885Y-42425D01*
X1149666Y-44467D01*
X1149885Y-46509D01*
X1150758Y-48259D01*
X1152068Y-49717D01*
X1153815Y-50300D01*
X1155343Y-49717D01*
X1156653Y-48550D01*
G01X1167385Y-42425D02*
X1174372D01*
X1173717Y-40383D01*
X1172625Y-39217D01*
X1171097Y-38634D01*
X1169568Y-38925D01*
X1168258Y-39800D01*
X1167385Y-41842D01*
X1166948Y-43592D01*
Y-45342D01*
X1167385Y-47092D01*
X1168477Y-48842D01*
X1169787Y-50008D01*
X1171315Y-50300D01*
X1172843Y-49717D01*
X1174372Y-47967D01*
G01X1184885Y-48259D02*
X1185977Y-49425D01*
X1187505Y-50300D01*
X1188815D01*
X1190125Y-49717D01*
X1190998Y-48842D01*
X1191435Y-47676D01*
X1191217Y-45925D01*
X1190343Y-45050D01*
X1186413Y-43300D01*
X1185540Y-41258D01*
X1185977Y-39800D01*
X1186850Y-38925D01*
X1188160Y-38634D01*
X1189470Y-38925D01*
X1190780Y-39800D01*
G01X1223160Y-38634D02*
Y-50300D01*
G01Y-33967D02*
X1222723Y-33675D01*
Y-33092D01*
X1223160Y-32800D01*
X1223597Y-33092D01*
Y-33675D01*
X1223160Y-33967D01*
G01X1236948Y-50300D02*
Y-38634D01*
G01Y-41550D02*
X1237822Y-40092D01*
X1239132Y-38925D01*
X1240878Y-38634D01*
X1242406Y-38925D01*
X1243717Y-40092D01*
X1244372Y-42133D01*
Y-50300D01*
G01X1275660D02*
Y-32800D01*
G01X1297090Y-50300D02*
Y-38634D01*
G01Y-40675D02*
X1296217Y-39509D01*
X1294906Y-38925D01*
X1293378Y-38634D01*
X1291850Y-39217D01*
X1290540Y-40383D01*
X1289666Y-42133D01*
X1289230Y-44467D01*
X1289666Y-46800D01*
X1290540Y-48550D01*
X1291850Y-49717D01*
X1293378Y-50300D01*
X1294906Y-50008D01*
X1296217Y-49134D01*
X1297090Y-47967D01*
G01X1306075Y-55550D02*
X1307385Y-56133D01*
X1309132Y-55550D01*
X1310223Y-54384D01*
X1311097Y-52925D01*
X1312406Y-48259D01*
X1315245Y-38634D01*
G01X1308258D02*
X1312406Y-48259D01*
G01X1324885Y-42425D02*
X1331872D01*
X1331217Y-40383D01*
X1330125Y-39217D01*
X1328597Y-38634D01*
X1327068Y-38925D01*
X1325758Y-39800D01*
X1324885Y-41842D01*
X1324448Y-43592D01*
Y-45342D01*
X1324885Y-47092D01*
X1325977Y-48842D01*
X1327287Y-50008D01*
X1328815Y-50300D01*
X1330343Y-49717D01*
X1331872Y-47967D01*
G01X1342603Y-50300D02*
Y-38634D01*
G01Y-40967D02*
X1343695Y-39800D01*
X1344787Y-38925D01*
X1346315Y-38634D01*
X1347406Y-38925D01*
X1348717Y-39800D01*
G01X1376293Y-32800D02*
Y-50300D01*
X1385027D01*
G01X1398160D02*
Y-32800D01*
X1395540Y-36300D01*
G01Y-50300D02*
X1400780D01*
G01X1415660Y-50883D02*
X1415223Y-50592D01*
Y-50008D01*
X1415660Y-49717D01*
X1416097Y-50008D01*
Y-50592D01*
X1415660Y-50883D01*
G01X617226Y709229D02*
X618973Y707771D01*
X620938Y706896D01*
X622684D01*
X624431Y707771D01*
X625741Y709229D01*
X626396Y711271D01*
X625959Y713312D01*
X624868Y715063D01*
X622903Y716229D01*
X620283Y716813D01*
X618754Y717979D01*
X618099Y720021D01*
X618536Y722063D01*
X619628Y723521D01*
X621156Y724396D01*
X622684D01*
X624213Y723813D01*
X625523Y722354D01*
G01X643678Y706896D02*
X634944D01*
Y724396D01*
X643678D01*
G01X640184Y715938D02*
X634944D01*
G01X671691Y724396D02*
X676931D01*
G01X674311D02*
Y706896D01*
G01X671691D02*
X676931D01*
G01X686134D02*
Y724396D01*
X691811Y709813D01*
X697488Y724396D01*
Y706896D01*
G01X704944D02*
Y724396D01*
X710184D01*
X711931Y723521D01*
X713241Y721479D01*
X713678Y719146D01*
X713241Y716813D01*
X712149Y715063D01*
X710184Y714187D01*
X704944D01*
G01X731178Y706896D02*
X722444D01*
Y724396D01*
X731178D01*
G01X727684Y715938D02*
X722444D01*
G01X739508Y706896D02*
Y724396D01*
X743874D01*
X745621Y723521D01*
X746931Y722354D01*
X748023Y720605D01*
X748896Y718562D01*
X749114Y715646D01*
X748896Y712729D01*
X748023Y710687D01*
X746931Y708937D01*
X745621Y707771D01*
X743874Y706896D01*
X739508D01*
G01X756352D02*
X761811Y724396D01*
X767270Y706896D01*
G01X765304Y713021D02*
X758317D01*
G01X774289Y706896D02*
Y724396D01*
X784333Y706896D01*
Y724396D01*
G01X801614Y722937D02*
X800304Y723813D01*
X798776Y724396D01*
X797029D01*
X795064Y723521D01*
X793536Y722063D01*
X792444Y720312D01*
X791571Y717396D01*
X791352Y714771D01*
X791789Y712146D01*
X792444Y710396D01*
X793754Y708646D01*
X795283Y707479D01*
X796811Y706896D01*
X798339D01*
X799868Y707479D01*
X801178Y708354D01*
X802270Y709520D01*
G01X818678Y706896D02*
X809944D01*
Y724396D01*
X818678D01*
G01X815184Y715938D02*
X809944D01*
G01X849311Y724396D02*
Y706896D01*
G01X844289Y724396D02*
X854333D01*
G01X861352Y706896D02*
X866811Y724396D01*
X872270Y706896D01*
G01X870304Y713021D02*
X863317D01*
G01X886057Y716229D02*
X886931Y717104D01*
X887586Y718562D01*
X888023Y720605D01*
X887586Y722354D01*
X886713Y723521D01*
X885184Y724396D01*
X879289D01*
Y706896D01*
X886494D01*
X888023Y708062D01*
X888896Y709813D01*
X889333Y711854D01*
X888896Y713896D01*
X887586Y715646D01*
X886057Y716229D01*
X879289D01*
G01X897444Y724396D02*
Y706896D01*
X906178D01*
G01X923678D02*
X914944D01*
Y724396D01*
X923678D01*
G01X920184Y715938D02*
X914944D01*
G01X936811Y706313D02*
X936374Y706604D01*
Y707188D01*
X936811Y707479D01*
X937248Y707188D01*
Y706604D01*
X936811Y706313D01*
G01Y714187D02*
X936374Y714479D01*
Y715063D01*
X936811Y715354D01*
X937248Y715063D01*
Y714479D01*
X936811Y714187D01*
G01X967444Y724396D02*
Y706896D01*
X976178D01*
G01X989311D02*
Y724396D01*
X986691Y720896D01*
G01Y706896D02*
X991931D01*
G01X638891Y689746D02*
X644131D01*
G01X641511D02*
Y672246D01*
G01X638891D02*
X644131D01*
G01X653334D02*
Y689746D01*
X659011Y675163D01*
X664688Y689746D01*
Y672246D01*
G01X672144D02*
Y689746D01*
X677384D01*
X679131Y688871D01*
X680441Y686829D01*
X680878Y684496D01*
X680441Y682163D01*
X679349Y680413D01*
X677384Y679537D01*
X672144D01*
G01X692919Y666413D02*
X690736Y669329D01*
X689644Y672246D01*
Y683912D01*
X690736Y686829D01*
X692919Y689746D01*
G01X711511Y672246D02*
X709764Y672538D01*
X708236Y673704D01*
X706926Y675454D01*
X706052Y677496D01*
X705616Y679829D01*
Y682163D01*
X706052Y684496D01*
X706926Y686538D01*
X708236Y688287D01*
X709764Y689454D01*
X711511Y689746D01*
X713257Y689454D01*
X714786Y688287D01*
X716096Y686538D01*
X716970Y684496D01*
X717406Y682163D01*
Y679829D01*
X716970Y677496D01*
X716096Y675454D01*
X714786Y673704D01*
X713257Y672538D01*
X711511Y672246D01*
G01X725299D02*
Y689746D01*
G01Y681288D02*
X726391Y682746D01*
X727483Y683621D01*
X729229Y683912D01*
X730539Y683621D01*
X732068Y682454D01*
X732723Y680704D01*
Y672246D01*
G01X739961D02*
Y683912D01*
G01Y680704D02*
X740616Y682163D01*
X741708Y683329D01*
X743236Y683912D01*
X744764Y683329D01*
X745856Y682163D01*
X746511Y680704D01*
Y672246D01*
G01Y680704D02*
X747166Y682163D01*
X748257Y683329D01*
X749786Y683912D01*
X751314Y683329D01*
X752406Y682163D01*
X753061Y680413D01*
Y672246D01*
G01X765103Y666413D02*
X767286Y669329D01*
X768378Y672246D01*
Y683912D01*
X767286Y686829D01*
X765103Y689746D01*
G01X671708Y640220D02*
X673017Y638762D01*
X674546Y637888D01*
X676511Y637596D01*
X678476Y638179D01*
X680004Y639346D01*
X681096Y641387D01*
X681314Y643721D01*
X680878Y646054D01*
X679786Y647513D01*
X678257Y648679D01*
X676729Y648971D01*
X675201Y648679D01*
X673236Y647513D01*
X673891Y655096D01*
X679786D01*
G01X694011D02*
X692264Y654513D01*
X690954Y653054D01*
X690081Y651305D01*
X689426Y648971D01*
X689208Y646346D01*
X689426Y643721D01*
X690081Y641387D01*
X690954Y639637D01*
X692264Y638179D01*
X694011Y637596D01*
X695757Y638179D01*
X697068Y639637D01*
X697941Y641387D01*
X698596Y643721D01*
X698814Y646346D01*
X698596Y648971D01*
X697941Y651305D01*
X697068Y653054D01*
X695757Y654513D01*
X694011Y655096D01*
G01X711511Y637013D02*
X711074Y637304D01*
Y637888D01*
X711511Y638179D01*
X711948Y637888D01*
Y637304D01*
X711511Y637013D01*
G01X729011Y655096D02*
X727264Y654513D01*
X725954Y653054D01*
X725081Y651305D01*
X724426Y648971D01*
X724208Y646346D01*
X724426Y643721D01*
X725081Y641387D01*
X725954Y639637D01*
X727264Y638179D01*
X729011Y637596D01*
X730757Y638179D01*
X732068Y639637D01*
X732941Y641387D01*
X733596Y643721D01*
X733814Y646346D01*
X733596Y648971D01*
X732941Y651305D01*
X732068Y653054D01*
X730757Y654513D01*
X729011Y655096D01*
G01X809961Y689746D02*
X813017Y672246D01*
X816511Y689746D01*
X820004Y672246D01*
X823061Y689746D01*
G01X831391D02*
X836631D01*
G01X834011D02*
Y672246D01*
G01X831391D02*
X836631D01*
G01X846708D02*
Y689746D01*
X851074D01*
X852821Y688871D01*
X854131Y687704D01*
X855223Y685955D01*
X856096Y683912D01*
X856314Y680996D01*
X856096Y678079D01*
X855223Y676037D01*
X854131Y674287D01*
X852821Y673121D01*
X851074Y672246D01*
X846708D01*
G01X869011Y689746D02*
Y672246D01*
G01X863989Y689746D02*
X874033D01*
G01X881926Y672246D02*
Y689746D01*
G01X891096D02*
Y672246D01*
G01Y680996D02*
X881926D01*
G01X902919Y666413D02*
X900736Y669329D01*
X899644Y672246D01*
Y683912D01*
X900736Y686829D01*
X902919Y689746D01*
G01X914961Y672246D02*
Y683912D01*
G01Y680704D02*
X915616Y682163D01*
X916708Y683329D01*
X918236Y683912D01*
X919764Y683329D01*
X920856Y682163D01*
X921511Y680704D01*
Y672246D01*
G01Y680704D02*
X922166Y682163D01*
X923257Y683329D01*
X924786Y683912D01*
X926314Y683329D01*
X927406Y682163D01*
X928061Y680413D01*
Y672246D01*
G01X939011Y683912D02*
Y672246D01*
G01Y688579D02*
X938574Y688871D01*
Y689454D01*
X939011Y689746D01*
X939448Y689454D01*
Y688871D01*
X939011Y688579D01*
G01X956511Y672246D02*
Y689746D01*
G01X970736Y674287D02*
X971828Y673121D01*
X973356Y672246D01*
X974666D01*
X975976Y672829D01*
X976849Y673704D01*
X977286Y674870D01*
X977068Y676621D01*
X976194Y677496D01*
X972264Y679246D01*
X971391Y681288D01*
X971828Y682746D01*
X972701Y683621D01*
X974011Y683912D01*
X975321Y683621D01*
X976631Y682746D01*
G01X992603Y666413D02*
X994786Y669329D01*
X995878Y672246D01*
Y683912D01*
X994786Y686829D01*
X992603Y689746D01*
G01X886074Y637596D02*
X886511Y641387D01*
X887166Y644596D01*
X888039Y647513D01*
X889131Y650721D01*
X890878Y655096D01*
X882144D01*
G01X904011Y637013D02*
X903574Y637304D01*
Y637888D01*
X904011Y638179D01*
X904448Y637888D01*
Y637304D01*
X904011Y637013D01*
G01X917363Y652179D02*
X918673Y653929D01*
X920201Y654804D01*
X921948Y655096D01*
X924131Y654513D01*
X925659Y653054D01*
X926096Y651305D01*
X925878Y649554D01*
X925004Y648096D01*
X920638Y645179D01*
X918673Y643138D01*
X917363Y640220D01*
X916926Y637596D01*
X926096D01*
G01X1044011Y689746D02*
Y672246D01*
G01X1038989Y689746D02*
X1049033D01*
G01X1061511Y672246D02*
Y680121D01*
X1057144Y689746D01*
G01X1065878D02*
X1061511Y680121D01*
G01X1074644Y672246D02*
Y689746D01*
X1079884D01*
X1081631Y688871D01*
X1082941Y686829D01*
X1083378Y684496D01*
X1082941Y682163D01*
X1081849Y680413D01*
X1079884Y679537D01*
X1074644D01*
G01X1100878Y672246D02*
X1092144D01*
Y689746D01*
X1100878D01*
G01X1097384Y681288D02*
X1092144D01*
G01X1056926Y639929D02*
X1058673Y638471D01*
X1060638Y637596D01*
X1062384D01*
X1064131Y638471D01*
X1065441Y639929D01*
X1066096Y641971D01*
X1065659Y644012D01*
X1064568Y645763D01*
X1062603Y646929D01*
X1059983Y647513D01*
X1058454Y648679D01*
X1057799Y650721D01*
X1058236Y652763D01*
X1059328Y654221D01*
X1060856Y655096D01*
X1062384D01*
X1063913Y654513D01*
X1065223Y653054D01*
G01X1083378Y637596D02*
X1074644D01*
Y655096D01*
X1083378D01*
G01X1079884Y646638D02*
X1074644D01*
G01X1144644Y672246D02*
Y689746D01*
X1150103D01*
X1151849Y688871D01*
X1152941Y687704D01*
X1153378Y685371D01*
X1152941Y683037D01*
X1151631Y681579D01*
X1150103Y680704D01*
X1144644D01*
G01X1150103D02*
X1153378Y672246D01*
G01X1163236Y680121D02*
X1170223D01*
X1169568Y682163D01*
X1168476Y683329D01*
X1166948Y683912D01*
X1165419Y683621D01*
X1164109Y682746D01*
X1163236Y680704D01*
X1162799Y678954D01*
Y677204D01*
X1163236Y675454D01*
X1164328Y673704D01*
X1165638Y672538D01*
X1167166Y672246D01*
X1168694Y672829D01*
X1170223Y674579D01*
G01X1182701Y672246D02*
Y687121D01*
X1183138Y688579D01*
X1184011Y689454D01*
X1185321Y689746D01*
X1186631Y689163D01*
X1187286Y687704D01*
G01X1184666Y682746D02*
X1180299D01*
G01X1201511Y671663D02*
X1201074Y671954D01*
Y672538D01*
X1201511Y672829D01*
X1201948Y672538D01*
Y671954D01*
X1201511Y671663D01*
G01X1232144Y672246D02*
Y689746D01*
X1237384D01*
X1239131Y688871D01*
X1240441Y686829D01*
X1240878Y684496D01*
X1240441Y682163D01*
X1239349Y680413D01*
X1237384Y679537D01*
X1232144D01*
G01X1254011Y672246D02*
Y689746D01*
G01X1275441Y672246D02*
Y683912D01*
G01Y681871D02*
X1274568Y683037D01*
X1273257Y683621D01*
X1271729Y683912D01*
X1270201Y683329D01*
X1268891Y682163D01*
X1268017Y680413D01*
X1267581Y678079D01*
X1268017Y675746D01*
X1268891Y673996D01*
X1270201Y672829D01*
X1271729Y672246D01*
X1273257Y672538D01*
X1274568Y673412D01*
X1275441Y674579D01*
G01X1285299Y672246D02*
Y683912D01*
G01Y680996D02*
X1286173Y682454D01*
X1287483Y683621D01*
X1289229Y683912D01*
X1290757Y683621D01*
X1292068Y682454D01*
X1292723Y680413D01*
Y672246D01*
G01X1303236Y680121D02*
X1310223D01*
X1309568Y682163D01*
X1308476Y683329D01*
X1306948Y683912D01*
X1305419Y683621D01*
X1304109Y682746D01*
X1303236Y680704D01*
X1302799Y678954D01*
Y677204D01*
X1303236Y675454D01*
X1304328Y673704D01*
X1305638Y672538D01*
X1307166Y672246D01*
X1308694Y672829D01*
X1310223Y674579D01*
G01X1214644Y655096D02*
Y637596D01*
X1223378D01*
G01X1232363Y652179D02*
X1233673Y653929D01*
X1235201Y654804D01*
X1236948Y655096D01*
X1239131Y654513D01*
X1240659Y653054D01*
X1241096Y651305D01*
X1240878Y649554D01*
X1240004Y648096D01*
X1235638Y645179D01*
X1233673Y643138D01*
X1232363Y640220D01*
X1231926Y637596D01*
X1241096D01*
G01X1424311Y649262D02*
Y637596D01*
G01Y653929D02*
X1423874Y654221D01*
Y654804D01*
X1424311Y655096D01*
X1424748Y654804D01*
Y654221D01*
X1424311Y653929D01*
G01X1438536Y639637D02*
X1439628Y638471D01*
X1441156Y637596D01*
X1442466D01*
X1443776Y638179D01*
X1444649Y639054D01*
X1445086Y640220D01*
X1444868Y641971D01*
X1443994Y642846D01*
X1440064Y644596D01*
X1439191Y646638D01*
X1439628Y648096D01*
X1440501Y648971D01*
X1441811Y649262D01*
X1443121Y648971D01*
X1444431Y648096D01*
G01X1471789Y637596D02*
Y655096D01*
X1481833Y637596D01*
Y655096D01*
G01X1494311Y637596D02*
X1492564Y637888D01*
X1491036Y639054D01*
X1489726Y640804D01*
X1488852Y642846D01*
X1488416Y645179D01*
Y647513D01*
X1488852Y649846D01*
X1489726Y651888D01*
X1491036Y653637D01*
X1492564Y654804D01*
X1494311Y655096D01*
X1496057Y654804D01*
X1497586Y653637D01*
X1498896Y651888D01*
X1499770Y649846D01*
X1500206Y647513D01*
Y645179D01*
X1499770Y642846D01*
X1498896Y640804D01*
X1497586Y639054D01*
X1496057Y637888D01*
X1494311Y637596D01*
G01X1511811Y655096D02*
Y637596D01*
G01X1506789Y655096D02*
X1516833D01*
G01X1543099Y649262D02*
Y641096D01*
X1543973Y639054D01*
X1545283Y637888D01*
X1546811Y637596D01*
X1548339Y637888D01*
X1549649Y639054D01*
X1550523Y641096D01*
G01Y637596D02*
Y649262D01*
G01X1561036Y639637D02*
X1562128Y638471D01*
X1563656Y637596D01*
X1564966D01*
X1566276Y638179D01*
X1567149Y639054D01*
X1567586Y640220D01*
X1567368Y641971D01*
X1566494Y642846D01*
X1562564Y644596D01*
X1561691Y646638D01*
X1562128Y648096D01*
X1563001Y648971D01*
X1564311Y649262D01*
X1565621Y648971D01*
X1566931Y648096D01*
G01X1578536Y645471D02*
X1585523D01*
X1584868Y647513D01*
X1583776Y648679D01*
X1582248Y649262D01*
X1580719Y648971D01*
X1579409Y648096D01*
X1578536Y646054D01*
X1578099Y644304D01*
Y642554D01*
X1578536Y640804D01*
X1579628Y639054D01*
X1580938Y637888D01*
X1582466Y637596D01*
X1583994Y638179D01*
X1585523Y639929D01*
G01X1603241Y655096D02*
Y637596D01*
G01Y640220D02*
X1602368Y638762D01*
X1601057Y637888D01*
X1599529Y637596D01*
X1597783Y638179D01*
X1596473Y639637D01*
X1595599Y641387D01*
X1595381Y643429D01*
X1595599Y645471D01*
X1596473Y647221D01*
X1597783Y648679D01*
X1599529Y649262D01*
X1601057Y648971D01*
X1602149Y648387D01*
X1603241Y647221D01*
G01X1349508Y671663D02*
X1359114Y684496D01*
G01X1354311Y686829D02*
Y669329D01*
G01X1359114Y671663D02*
X1349508Y684496D01*
G01X1347761Y678079D02*
X1360861D01*
G01X1386473D02*
X1392149D01*
G01X1419508Y672246D02*
Y689746D01*
X1423874D01*
X1425621Y688871D01*
X1426931Y687704D01*
X1428023Y685955D01*
X1428896Y683912D01*
X1429114Y680996D01*
X1428896Y678079D01*
X1428023Y676037D01*
X1426931Y674287D01*
X1425621Y673121D01*
X1423874Y672246D01*
X1419508D01*
G01X1438536Y680121D02*
X1445523D01*
X1444868Y682163D01*
X1443776Y683329D01*
X1442248Y683912D01*
X1440719Y683621D01*
X1439409Y682746D01*
X1438536Y680704D01*
X1438099Y678954D01*
Y677204D01*
X1438536Y675454D01*
X1439628Y673704D01*
X1440938Y672538D01*
X1442466Y672246D01*
X1443994Y672829D01*
X1445523Y674579D01*
G01X1455599Y672246D02*
Y683912D01*
G01Y680996D02*
X1456473Y682454D01*
X1457783Y683621D01*
X1459529Y683912D01*
X1461057Y683621D01*
X1462368Y682454D01*
X1463023Y680413D01*
Y672246D01*
G01X1476811D02*
X1475501Y672538D01*
X1474191Y673704D01*
X1473317Y675746D01*
X1472881Y678079D01*
X1473317Y680413D01*
X1474191Y682454D01*
X1475501Y683621D01*
X1476811Y683912D01*
X1478121Y683621D01*
X1479431Y682454D01*
X1480304Y680413D01*
X1480523Y678079D01*
X1480304Y675746D01*
X1479431Y673704D01*
X1478121Y672538D01*
X1476811Y672246D01*
G01X1494311Y689746D02*
Y672246D01*
G01X1491254Y683912D02*
X1497368D01*
G01X1508536Y680121D02*
X1515523D01*
X1514868Y682163D01*
X1513776Y683329D01*
X1512248Y683912D01*
X1510719Y683621D01*
X1509409Y682746D01*
X1508536Y680704D01*
X1508099Y678954D01*
Y677204D01*
X1508536Y675454D01*
X1509628Y673704D01*
X1510938Y672538D01*
X1512466Y672246D01*
X1513994Y672829D01*
X1515523Y674579D01*
G01X1526036Y674287D02*
X1527128Y673121D01*
X1528656Y672246D01*
X1529966D01*
X1531276Y672829D01*
X1532149Y673704D01*
X1532586Y674870D01*
X1532368Y676621D01*
X1531494Y677496D01*
X1527564Y679246D01*
X1526691Y681288D01*
X1527128Y682746D01*
X1528001Y683621D01*
X1529311Y683912D01*
X1530621Y683621D01*
X1531931Y682746D01*
G01X1564311Y689746D02*
Y672246D01*
G01X1561254Y683912D02*
X1567368D01*
G01X1578099Y672246D02*
Y689746D01*
G01Y681288D02*
X1579191Y682746D01*
X1580283Y683621D01*
X1582029Y683912D01*
X1583339Y683621D01*
X1584868Y682454D01*
X1585523Y680704D01*
Y672246D01*
G01X1603241D02*
Y683912D01*
G01Y681871D02*
X1602368Y683037D01*
X1601057Y683621D01*
X1599529Y683912D01*
X1598001Y683329D01*
X1596691Y682163D01*
X1595817Y680413D01*
X1595381Y678079D01*
X1595817Y675746D01*
X1596691Y673996D01*
X1598001Y672829D01*
X1599529Y672246D01*
X1601057Y672538D01*
X1602368Y673412D01*
X1603241Y674579D01*
G01X1616811Y689746D02*
Y672246D01*
G01X1613754Y683912D02*
X1619868D01*
G01X1651811Y689746D02*
Y672246D01*
G01X1648754Y683912D02*
X1654868D01*
G01X1665599Y672246D02*
Y689746D01*
G01Y681288D02*
X1666691Y682746D01*
X1667783Y683621D01*
X1669529Y683912D01*
X1670839Y683621D01*
X1672368Y682454D01*
X1673023Y680704D01*
Y672246D01*
G01X1686811Y683912D02*
Y672246D01*
G01Y688579D02*
X1686374Y688871D01*
Y689454D01*
X1686811Y689746D01*
X1687248Y689454D01*
Y688871D01*
X1686811Y688579D01*
G01X1701036Y674287D02*
X1702128Y673121D01*
X1703656Y672246D01*
X1704966D01*
X1706276Y672829D01*
X1707149Y673704D01*
X1707586Y674870D01*
X1707368Y676621D01*
X1706494Y677496D01*
X1702564Y679246D01*
X1701691Y681288D01*
X1702128Y682746D01*
X1703001Y683621D01*
X1704311Y683912D01*
X1705621Y683621D01*
X1706931Y682746D01*
G01X1736691Y689746D02*
X1741931D01*
G01X1739311D02*
Y672246D01*
G01X1736691D02*
X1741931D01*
G01X1750261D02*
Y683912D01*
G01Y680704D02*
X1750916Y682163D01*
X1752008Y683329D01*
X1753536Y683912D01*
X1755064Y683329D01*
X1756156Y682163D01*
X1756811Y680704D01*
Y672246D01*
G01Y680704D02*
X1757466Y682163D01*
X1758557Y683329D01*
X1760086Y683912D01*
X1761614Y683329D01*
X1762706Y682163D01*
X1763361Y680413D01*
Y672246D01*
G01X1770381Y666413D02*
Y683912D01*
G01Y681288D02*
X1771473Y682746D01*
X1772564Y683621D01*
X1774311Y683912D01*
X1775839Y683621D01*
X1777368Y682163D01*
X1778023Y680121D01*
X1778241Y678079D01*
X1778023Y676037D01*
X1777368Y673996D01*
X1776057Y672829D01*
X1774311Y672246D01*
X1772783Y672538D01*
X1771254Y673412D01*
X1770381Y674579D01*
G01X1788536Y680121D02*
X1795523D01*
X1794868Y682163D01*
X1793776Y683329D01*
X1792248Y683912D01*
X1790719Y683621D01*
X1789409Y682746D01*
X1788536Y680704D01*
X1788099Y678954D01*
Y677204D01*
X1788536Y675454D01*
X1789628Y673704D01*
X1790938Y672538D01*
X1792466Y672246D01*
X1793994Y672829D01*
X1795523Y674579D01*
G01X1813241Y689746D02*
Y672246D01*
G01Y674870D02*
X1812368Y673412D01*
X1811057Y672538D01*
X1809529Y672246D01*
X1807783Y672829D01*
X1806473Y674287D01*
X1805599Y676037D01*
X1805381Y678079D01*
X1805599Y680121D01*
X1806473Y681871D01*
X1807783Y683329D01*
X1809529Y683912D01*
X1811057Y683621D01*
X1812149Y683037D01*
X1813241Y681871D01*
G01X1830741Y672246D02*
Y683912D01*
G01Y681871D02*
X1829868Y683037D01*
X1828557Y683621D01*
X1827029Y683912D01*
X1825501Y683329D01*
X1824191Y682163D01*
X1823317Y680413D01*
X1822881Y678079D01*
X1823317Y675746D01*
X1824191Y673996D01*
X1825501Y672829D01*
X1827029Y672246D01*
X1828557Y672538D01*
X1829868Y673412D01*
X1830741Y674579D01*
G01X1840599Y672246D02*
Y683912D01*
G01Y680996D02*
X1841473Y682454D01*
X1842783Y683621D01*
X1844529Y683912D01*
X1846057Y683621D01*
X1847368Y682454D01*
X1848023Y680413D01*
Y672246D01*
G01X1865304Y682454D02*
X1863776Y683621D01*
X1862466Y683912D01*
X1860719Y683329D01*
X1859409Y682163D01*
X1858536Y680121D01*
X1858317Y678079D01*
X1858536Y676037D01*
X1859409Y674287D01*
X1860719Y672829D01*
X1862466Y672246D01*
X1863994Y672829D01*
X1865304Y673996D01*
G01X1876036Y680121D02*
X1883023D01*
X1882368Y682163D01*
X1881276Y683329D01*
X1879748Y683912D01*
X1878219Y683621D01*
X1876909Y682746D01*
X1876036Y680704D01*
X1875599Y678954D01*
Y677204D01*
X1876036Y675454D01*
X1877128Y673704D01*
X1878438Y672538D01*
X1879966Y672246D01*
X1881494Y672829D01*
X1883023Y674579D01*
G01X-25590Y9843D02*
G03X-15748Y0I9842J-1D01*
G01X-25590Y89370D02*
Y9843D01*
G01X-23622Y91339D02*
G03X-25590Y89370I1J-1969D01*
G01X-7874Y91339D02*
X-23622D01*
G01X-25590Y109055D02*
G03X-21653Y105118I3937J0D01*
G01X-25590Y357874D02*
Y109055D01*
G01X-21653Y105118D02*
X261811D01*
G01X-25590Y371654D02*
G03X-23622Y369685I1968J-1D01*
G01X-21653Y361811D02*
G03X-25590Y357874I0J-3937D01*
G01X1969Y361811D02*
X-21653D01*
G01X-7874Y369685D02*
X-23622D01*
G01X-25590Y459055D02*
Y371654D01*
G01X-23622Y461024D02*
G03X-25590Y459055I1J-1969D01*
G01X-7874Y461024D02*
X-23622D01*
G01X-25590Y478740D02*
G03X-21653Y474803I3937J0D01*
G01X-25590Y727559D02*
Y478740D01*
G01X-21653Y474803D02*
X261811D01*
G01X-21653Y731496D02*
G03X-25590Y727559I0J-3937D01*
G01X1969Y731496D02*
X-21653D01*
G01X-11811Y0D02*
G03X-7874Y3937I0J3937D01*
G01X-11811Y0D02*
X-15748D01*
G01X0Y3937D02*
G03X3937Y0I3937J0D01*
G01X-7874Y33071D02*
Y3937D01*
G01X0Y87402D02*
Y3937D01*
G01Y33071D02*
G03X-7874I-3937J0D01*
G01Y58268D02*
G03X0I3937J0D01*
G01X-7874Y91339D02*
Y58268D01*
G01X3937Y91339D02*
G03X0Y87402I0J-3937D01*
G01X5906Y357874D02*
G03X1969Y361811I-3937J0D01*
G01X0Y373622D02*
G03X3937Y369685I3937J0D01*
G01X-7874Y402756D02*
Y369685D01*
G01X0Y457087D02*
Y373622D01*
G01Y402756D02*
G03X-7874I-3937J0D01*
G01Y427953D02*
G03X0I3937J0D01*
G01X-7874Y461024D02*
Y427953D01*
G01X3937Y461024D02*
G03X0Y457087I0J-3937D01*
G01X5906Y727559D02*
G03X1969Y731496I-3937J0D01*
G01X3937Y0D02*
X372048D01*
G01X192914Y91339D02*
X3937D01*
G01X5906Y290748D02*
G03X9843Y286811I3937J0D01*
G01X5906Y357874D02*
Y290748D01*
G01X69488Y286811D02*
X9843D01*
G01X13780Y315650D02*
Y294685D01*
G01X69488D02*
X13780D01*
G01Y315650D02*
G03X5906I-3937J0D01*
G01Y340847D02*
G03X13780I3937J0D01*
G01Y361811D02*
Y340847D01*
G01X3937Y369685D02*
X372048D01*
G01X43307Y361811D02*
X13780D01*
G01X192914Y461024D02*
X3937D01*
G01X5906Y660433D02*
G03X9843Y656496I3937J0D01*
G01X5906Y727559D02*
Y660433D01*
G01X69488Y656496D02*
X9843D01*
G01X13780Y685335D02*
Y664370D01*
G01X69488D02*
X13780D01*
G01Y685335D02*
G03X5906I-3937J0D01*
G01Y710532D02*
G03X13780I3937J0D01*
G01Y729528D02*
Y710532D01*
G01X15748Y731496D02*
G03X13780Y729528I0J-1968D01*
G01X44819Y731496D02*
X15748D01*
G01X43307Y361811D02*
G03Y369685I0J3937D01*
G01X46675Y730184D02*
G03X44819Y731496I-1856J-657D01*
G01X46675Y730184D02*
G03X54098I3712J1313D01*
G01X53150Y181697D02*
G03X55118Y179729I1968J0D01*
G01X53150Y195477D02*
Y181697D01*
G01X55118Y179729D02*
X161418D01*
G01X55118Y197445D02*
G03X53150Y195477I0J-1968D01*
G01X161418Y197445D02*
X55118D01*
G01X73426Y282874D02*
G03X69488Y286811I-3937J0D01*
G01X81300Y282874D02*
G03X69488Y294685I-11811J0D01*
G01X74016Y369685D02*
G03Y361811I0J-3937D01*
G01X53150Y551382D02*
G03X55118Y549414I1968J0D01*
G01X53150Y565162D02*
Y551382D01*
G01X55118Y549414D02*
X161418D01*
G01X55118Y567130D02*
G03X53150Y565162I0J-1968D01*
G01X161418Y567130D02*
X55118D01*
G01X73426Y652559D02*
G03X69488Y656496I-3937J0D01*
G01X81300Y652559D02*
G03X69488Y664370I-11811J0D01*
G01X55954Y731496D02*
G03X54098Y730184I0J-1969D01*
G01X153544Y731496D02*
X55954D01*
G01X80709Y43307D02*
G03X82677Y41339I1968J0D01*
G01Y47244D02*
G03X80709Y45276I0J-1968D01*
G01X188977Y47244D02*
X82677D01*
G01Y41339D02*
X188977D01*
G01X80709Y45276D02*
Y43307D01*
G01X86614Y101181D02*
G03X82677Y105118I-3937J0D01*
G01X86614Y95276D02*
Y101181D01*
G01X82677Y91339D02*
G03X86614Y95276I0J3937D01*
G01X73426Y267323D02*
G03X77363Y263386I3937J0D01*
G01X73426Y267323D02*
Y282874D01*
G01X77363Y263386D02*
X159449D01*
G01X81300Y271260D02*
Y282874D01*
G01Y271260D02*
X155512D01*
G01Y361811D02*
X74016D01*
G01X80709Y412992D02*
G03X82677Y411024I1968J0D01*
G01Y416929D02*
G03X80709Y414961I0J-1968D01*
G01X188977Y416929D02*
X82677D01*
G01Y411024D02*
X188977D01*
G01X80709Y414961D02*
Y412992D01*
G01X86614Y464961D02*
Y470866D01*
G01X82677Y461024D02*
G03X86614Y464961I0J3937D01*
G01Y470866D02*
G03X82677Y474803I-3937J0D01*
G01X73426Y637008D02*
G03X77363Y633071I3937J0D01*
G01X73426Y637008D02*
Y652559D01*
G01X77363Y633071D02*
X159449D01*
G01X81300Y640945D02*
Y652559D01*
G01Y640945D02*
X155512D01*
G01X109449Y95276D02*
Y101181D01*
G01X113386Y105118D02*
G03X109449Y101181I0J-3937D01*
G01Y95276D02*
G03X113386Y91339I3937J0D01*
G01X109449Y464961D02*
Y470866D01*
G01Y464961D02*
G03X113386Y461024I3937J0D01*
G01Y474803D02*
G03X109449Y470866I0J-3937D01*
G01X161418Y179729D02*
G03X163386Y181697I0J1968D01*
G01Y195477D02*
G03X161418Y197445I-1968J0D01*
G01X159449Y263386D02*
G03X163386Y267323I0J3937D01*
G01X155512Y303937D02*
Y271260D01*
G01X163386Y303937D02*
G03X155512I-3937J0D01*
G01Y329134D02*
G03X163386I3937J0D01*
G01X155512Y361811D02*
Y329134D01*
G01X161418Y549414D02*
G03X163386Y551382I0J1968D01*
G01Y565162D02*
G03X161418Y567130I-1968J0D01*
G01X159449Y633071D02*
G03X163386Y637008I0J3937D01*
G01X155512Y673622D02*
Y640945D01*
G01X163386Y673622D02*
G03X155512I-3937J0D01*
G01Y698819D02*
G03X163386I3937J0D01*
G01X155512Y729528D02*
Y698819D01*
G01Y729528D02*
G03X153544Y731496I-1968J0D01*
G01X163386Y181697D02*
Y195477D01*
G01Y357874D02*
Y267323D01*
G01X167323Y361811D02*
G03X163386Y357874I0J-3937D01*
G01X535433Y361811D02*
X167323D01*
G01X163386Y551382D02*
Y565162D01*
G01Y727559D02*
Y637008D01*
G01X167323Y731496D02*
G03X163386Y727559I0J-3937D01*
G01X535433Y731496D02*
X167323D01*
G01X188977Y41339D02*
G03X190945Y43307I0J1968D01*
G01Y45276D02*
G03X188977Y47244I-1968J0D01*
G01X190945Y43307D02*
Y45276D01*
G01X196851Y97244D02*
G03X194882Y95276I0J-1969D01*
G01X192914Y91339D02*
G03X194882Y93307I0J1968D01*
G01X196851Y97244D02*
X269685D01*
G01X194882Y93307D02*
Y95276D01*
G01X188977Y411024D02*
G03X190945Y412992I0J1968D01*
G01Y414961D02*
G03X188977Y416929I-1968J0D01*
G01X190945Y412992D02*
Y414961D01*
G01X196851Y466929D02*
G03X194882Y464961I-1J-1968D01*
G01X192914Y461024D02*
G03X194882Y462992I0J1968D01*
G01D02*
Y464961D01*
G01X196851Y466929D02*
X269685D01*
G01Y97244D02*
G03X273622Y101181I0J3937D01*
G01Y252756D02*
Y101181D01*
G01X261811Y105118D02*
G03X265748Y109055I0J3937D01*
G01D02*
Y260630D01*
G01X273622Y165551D02*
G03X265748I-3937J0D01*
G01Y196260D02*
G03X273622I3937J0D01*
G01X269685Y264567D02*
G03X265748Y260630I0J-3937D01*
G01X277559Y256693D02*
G03X273622Y252756I0J-3937D01*
G01X342520Y264567D02*
X269685D01*
G01X254331Y361811D02*
G03Y369685I0J3937D01*
G01X261811Y474803D02*
G03X265748Y478740I0J3937D01*
G01D02*
Y630315D01*
G01X269685Y466929D02*
G03X273622Y470866I0J3937D01*
G01Y622441D02*
Y470866D01*
G01Y535236D02*
G03X265748I-3937J0D01*
G01Y565945D02*
G03X273622I3937J0D01*
G01X277559Y626378D02*
G03X273622Y622441I0J-3937D01*
G01X269685Y634252D02*
G03X265748Y630315I0J-3937D01*
G01X342520Y634252D02*
X269685D01*
G01X561024Y256693D02*
X277559D01*
G01X285040Y369685D02*
G03Y361811I0J-3937D01*
G01X561024Y626378D02*
X277559D01*
G01X342520Y264567D02*
G03X344488Y266536I0J1968D01*
G01X342520Y634252D02*
G03X344488Y636221I0J1968D01*
G01X346457Y270473D02*
G03X344488Y268504I0J-1969D01*
G01X346457Y270473D02*
X535433D01*
G01X344488Y268504D02*
Y266536D01*
G01X350394Y320473D02*
G03X348426Y318504I0J-1968D01*
G01Y316536D02*
G03X350394Y314567I1968J-1D01*
G01D02*
X456693D01*
G01Y320473D02*
X350394D01*
G01X348426Y318504D02*
Y316536D01*
G01X346457Y640158D02*
G03X344488Y638189I0J-1969D01*
G01X346457Y640158D02*
X535433D01*
G01X344488Y638189D02*
Y636221D01*
G01X350394Y690158D02*
G03X348426Y688189I0J-1968D01*
G01Y686221D02*
G03X350394Y684252I1968J-1D01*
G01D02*
X456693D01*
G01Y690158D02*
X350394D01*
G01X348426Y688189D02*
Y686221D01*
G01X383859Y1969D02*
G03X385827Y0I1968J-1D01*
G01D02*
X523622D01*
G01X372048D02*
G03X375985Y3937I0J3937D01*
G01X383859Y1969D02*
Y32677D01*
G01X375985Y3937D02*
Y94488D01*
G01X383859Y32677D02*
G03X375985I-3937J0D01*
G01Y57874D02*
G03X383859I3937J0D01*
G01D02*
Y90551D01*
G01X379922Y98425D02*
G03X375985Y94488I0J-3937D01*
G01X458071Y90551D02*
X383859D01*
G01X462008Y98425D02*
X379922D01*
G01X375985Y166334D02*
G03X377953Y164365I1969J0D01*
G01X375985Y180113D02*
Y166334D01*
G01X377953Y164365D02*
X484252D01*
G01X377953Y182082D02*
G03X375985Y180113I0J-1968D01*
G01X484252Y182082D02*
X377953D01*
G01X383859Y369685D02*
X465355D01*
G01X372048D02*
G03X375985Y373622I0J3937D01*
G01X383859Y369685D02*
Y402362D01*
G01X375985Y373622D02*
Y464173D01*
G01X383859Y402362D02*
G03X375985I-3937J0D01*
G01Y427559D02*
G03X383859I3937J0D01*
G01D02*
Y460236D01*
G01X379922Y468110D02*
G03X375985Y464173I0J-3937D01*
G01X458071Y460236D02*
X383859D01*
G01X462008Y468110D02*
X379922D01*
G01X375985Y536019D02*
G03X377953Y534050I1969J0D01*
G01D02*
X484252D01*
G01X377953Y551767D02*
G03X375985Y549799I0J-1968D01*
G01D02*
Y536019D01*
G01X484252Y551767D02*
X377953D01*
G01X429922Y260630D02*
Y266536D01*
G01X425985Y256693D02*
G03X429922Y260630I0J3937D01*
G01Y266536D02*
G03X425985Y270473I-3937J0D01*
G01X429922Y630315D02*
Y636221D01*
G01X425985Y626378D02*
G03X429922Y630315I0J3937D01*
G01Y636221D02*
G03X425985Y640158I-3937J0D01*
G01X452756Y260630D02*
G03X456693Y256693I3937J0D01*
G01X452756Y260630D02*
Y266536D01*
G01X456693Y270473D02*
G03X452756Y266536I0J-3937D01*
G01X458662Y318504D02*
G03X456693Y320473I-1969J0D01*
G01Y314567D02*
G03X458662Y316536I0J1969D01*
G01X452756Y630315D02*
G03X456693Y626378I3937J0D01*
G01X452756Y630315D02*
Y636221D01*
G01X456693Y640158D02*
G03X452756Y636221I0J-3937D01*
G01X458662Y688189D02*
G03X456693Y690158I-1969J0D01*
G01Y684252D02*
G03X458662Y686221I0J1969D01*
G01X458071Y78937D02*
G03X469882Y67126I11811J0D01*
G01X465945Y78937D02*
G03X469882Y75000I3937J0D01*
G01X458071Y90551D02*
Y78937D01*
G01X465945Y94488D02*
Y78937D01*
G01X469882Y67126D02*
X525591D01*
G01X469882Y75000D02*
X529528D01*
G01X465945Y94488D02*
G03X462008Y98425I-3937J0D01*
G01X458662Y316536D02*
Y318504D01*
G01X465355Y361811D02*
G03Y369685I0J3937D01*
G01X458071Y448622D02*
G03X469882Y436811I11811J0D01*
G01D02*
X525591D01*
G01X465945Y448622D02*
G03X469882Y444685I3937J0D01*
G01X465945Y464173D02*
G03X462008Y468110I-3937J0D01*
G01X458071Y460236D02*
Y448622D01*
G01X465945Y464173D02*
Y448622D01*
G01X469882Y444685D02*
X529528D01*
G01X458662Y686221D02*
Y688189D01*
G01X484252Y164365D02*
G03X486221Y166334I0J1969D01*
G01D02*
Y180113D01*
G01D02*
G03X484252Y182082I-1969J0D01*
G01X496063Y369685D02*
G03Y361811I0J-3937D01*
G01Y369685D02*
X525591D01*
G01X484252Y534050D02*
G03X486221Y536019I0J1969D01*
G01Y549799D02*
G03X484252Y551767I-1969J-1D01*
G01X486221Y536019D02*
Y549799D01*
G01X523622Y0D02*
G03X525591Y1969I0J1969D01*
G01X533465Y3937D02*
G03X537402Y0I3937J0D01*
G01X525591Y1969D02*
Y20965D01*
G01X533465Y3937D02*
Y71063D01*
G01X537402Y0D02*
X561024D01*
G01X533465Y20965D02*
G03X525591I-3937J0D01*
G01Y46162D02*
G03X533465I3937J0D01*
G01X525591D02*
Y67126D01*
G01X533465Y71063D02*
G03X529528Y75000I-3937J0D01*
G01X535433Y270473D02*
G03X539370Y274410I0J3937D01*
G01D02*
Y357874D01*
G01X547244Y270473D02*
X562992D01*
G01X547244D02*
Y303543D01*
G01D02*
G03X539370I-3937J0D01*
G01Y328740D02*
G03X547244I3937J0D01*
G01D02*
Y361811D01*
G01X539370Y357874D02*
G03X535433Y361811I-3937J0D01*
G01X547244D02*
X562992D01*
G01X533465Y373622D02*
G03X537402Y369685I3937J0D01*
G01X525591D02*
Y390650D01*
G01X533465Y373622D02*
Y440748D01*
G01X537402Y369685D02*
X561024D01*
G01X533465Y390650D02*
G03X525591I-3937J0D01*
G01Y415847D02*
G03X533465I3937J0D01*
G01X525591D02*
Y436811D01*
G01X533465Y440748D02*
G03X529528Y444685I-3937J0D01*
G01X535433Y640158D02*
G03X539370Y644095I0J3937D01*
G01D02*
Y727559D01*
G01X547244Y640158D02*
X562992D01*
G01X547244D02*
Y673228D01*
G01D02*
G03X539370I-3937J0D01*
G01Y698425D02*
G03X547244I3937J0D01*
G01D02*
Y727559D01*
G01X551181Y731496D02*
G03X547244Y727559I0J-3937D01*
G01X539370D02*
G03X535433Y731496I-3937J0D01*
G01X561024Y0D02*
G03X564961Y3937I0J3937D01*
G01D02*
Y252756D01*
G01D02*
G03X561024Y256693I-3937J0D01*
G01X562992Y270473D02*
G03X564961Y272441I1J1968D01*
G01D02*
Y359843D01*
G01D02*
G03X562992Y361811I-1968J0D01*
G01X561024Y369685D02*
G03X564961Y373622I0J3937D01*
G01D02*
Y622441D01*
G01D02*
G03X561024Y626378I-3937J0D01*
G01X562992Y640158D02*
G03X564961Y642126I1J1968D01*
G01D02*
Y721654D01*
G01D02*
G03X555118Y731496I-9842J0D01*
G01X551181D02*
X555118D01*
G54D12*
G01X305250Y32000D02*
Y30250D01*
G01D02*
X303900Y28900D01*
G01X320965Y32050D02*
Y27735D01*
G01D02*
X322100Y26600D01*
G01X308750Y32000D02*
X313250D01*
G01D02*
Y27850D01*
G01D02*
X313900Y27200D01*
M02*
